(kicad_pcb
	(version 20260206)
	(generator "pcbnew")
	(generator_version "10.0")
	(general
		(thickness 1.6)
		(legacy_teardrops no)
	)
	(paper "A4")
	(title_block
		(title "panther-plus-userver — 13130-1b_20150205.brd")
		(comment 1 "Honey Badger (Wiwynn) / footprints 730-736 of 1509")
	)
	(layers
		(0 "F.Cu" signal "TOP")
		(4 "In1.Cu" signal "L2")
		(6 "In2.Cu" signal "L3")
		(8 "In3.Cu" signal "L4")
		(10 "In4.Cu" signal "L5")
		(12 "In5.Cu" signal "L6")
		(14 "In6.Cu" signal "L7")
		(16 "In7.Cu" signal "L8")
		(18 "In8.Cu" signal "L9")
		(20 "In9.Cu" signal "L10")
		(22 "In10.Cu" signal "L11")
		(2 "B.Cu" signal "BOTTOM")
		(9 "F.Adhes" user "F.Adhesive")
		(11 "B.Adhes" user "B.Adhesive")
		(13 "F.Paste" user "Package Geometry/Pastemask Top")
		(15 "B.Paste" user "Package Geometry/Pastemask Bottom")
		(5 "F.SilkS" user "Ref Des/Silkscreen Top")
		(7 "B.SilkS" user "Ref Des/Silkscreen Bottom")
		(1 "F.Mask" user "Board Geometry/Soldermask Top")
		(3 "B.Mask" user "Board Geometry/Soldermask Bottom")
		(17 "Dwgs.User" user "User.Drawings")
		(19 "Cmts.User" user "User.Comments")
		(21 "Eco1.User" user "User.Eco1")
		(23 "Eco2.User" user "User.Eco2")
		(25 "Edge.Cuts" user "Board Geometry/Outline")
		(27 "Margin" user)
		(31 "F.CrtYd" user "Package Geometry/Place Bound Top")
		(29 "B.CrtYd" user "Package Geometry/Place Bound Bottom")
		(35 "F.Fab" user "Ref Des/Assembly Top")
		(33 "B.Fab" user "Ref Des/Assembly Bottom")
	)
	(footprint ""
		(layer "F.Cu")
		(at 174.879 -57.15)
		(property "Reference" "R176"
			(at 0 0 0)
			(layer "F.SilkS")
			(hide yes)
			(effects
				(font
					(size 1.27 1.27)
				)
			)
		)
		(property "Value" "4K7R2F-GP"
			(at 0.064008 -3.993896 0)
			(unlocked yes)
			(layer "F.Fab")
			(hide yes)
			(effects
				(font
					(size 1.016 1.016)
					(thickness 0.1524)
				)
			)
		)
		(property "Device Type" "R402H16"
			(at 0.064008 -5.517896 0)
			(unlocked yes)
			(layer "F.Fab")
			(hide yes)
			(effects
				(font
					(size 1.016 1.016)
					(thickness 0.1524)
				)
			)
		)
		(duplicate_pad_numbers_are_jumpers no)
		(fp_rect
			(start -0.381 0.8382)
			(end 0.381 -0.8382)
			(stroke
				(width 0)
				(type default)
			)
			(fill no)
			(layer "F.CrtYd")
		)
		(fp_rect
			(start -0.381 0.8382)
			(end 0.381 -0.8382)
			(stroke
				(width 0)
				(type default)
			)
			(fill no)
			(layer "F.Fab")
		)
		(pad "1" smd custom
			(at 0 -0.4318)
			(size 0.127 0.127)
			(layers "F.Cu" "F.Mask" "F.Paste")
			(net "P3V3_STBY")
			(options
				(clearance outline)
				(anchor circle)
			)
			(primitives
				(gr_poly
					(pts
						(arc
							(start -0.2032 -0.2794)
							(mid -0.239121 -0.264521)
							(end -0.254 -0.2286)
						)
						(arc
							(start -0.254 0.2286)
							(mid -0.239121 0.264521)
							(end -0.2032 0.2794)
						)
						(arc
							(start 0.2032 0.2794)
							(mid 0.239121 0.264521)
							(end 0.254 0.2286)
						)
						(arc
							(start 0.254 -0.2286)
							(mid 0.239121 -0.264521)
							(end 0.2032 -0.2794)
						)
					)
					(width 0)
					(fill yes)
				)
			)
		)
		(pad "2" smd custom
			(at 0 0.4318)
			(size 0.127 0.127)
			(layers "F.Cu" "F.Mask" "F.Paste")
			(net "EEPROM_A1")
			(options
				(clearance outline)
				(anchor circle)
			)
			(primitives
				(gr_poly
					(pts
						(arc
							(start -0.2032 -0.2794)
							(mid -0.239121 -0.264521)
							(end -0.254 -0.2286)
						)
						(arc
							(start -0.254 0.2286)
							(mid -0.239121 0.264521)
							(end -0.2032 0.2794)
						)
						(arc
							(start 0.2032 0.2794)
							(mid 0.239121 0.264521)
							(end 0.254 0.2286)
						)
						(arc
							(start 0.254 -0.2286)
							(mid 0.239121 -0.264521)
							(end 0.2032 -0.2794)
						)
					)
					(width 0)
					(fill yes)
				)
			)
		)
	)
	(footprint ""
		(layer "F.Cu")
		(at 97.155 -14.097)
		(property "Reference" "R194"
			(at 0 0 0)
			(layer "F.SilkS")
			(hide yes)
			(effects
				(font
					(size 1.27 1.27)
				)
			)
		)
		(property "Value" "0R2J-2-GP"
			(at 0.064008 -3.993896 0)
			(unlocked yes)
			(layer "F.Fab")
			(hide yes)
			(effects
				(font
					(size 1.016 1.016)
					(thickness 0.1524)
				)
			)
		)
		(property "Device Type" "R402H16"
			(at 0.064008 -5.517896 0)
			(unlocked yes)
			(layer "F.Fab")
			(hide yes)
			(effects
				(font
					(size 1.016 1.016)
					(thickness 0.1524)
				)
			)
		)
		(duplicate_pad_numbers_are_jumpers no)
		(fp_rect
			(start -0.381 0.8382)
			(end 0.381 -0.8382)
			(stroke
				(width 0)
				(type default)
			)
			(fill no)
			(layer "F.CrtYd")
		)
		(fp_rect
			(start -0.381 0.8382)
			(end 0.381 -0.8382)
			(stroke
				(width 0)
				(type default)
			)
			(fill no)
			(layer "F.Fab")
		)
		(pad "1" smd custom
			(at 0 -0.4318)
			(size 0.127 0.127)
			(layers "F.Cu" "F.Mask" "F.Paste")
			(net "GND")
			(options
				(clearance outline)
				(anchor circle)
			)
			(primitives
				(gr_poly
					(pts
						(arc
							(start -0.2032 -0.2794)
							(mid -0.239121 -0.264521)
							(end -0.254 -0.2286)
						)
						(arc
							(start -0.254 0.2286)
							(mid -0.239121 0.264521)
							(end -0.2032 0.2794)
						)
						(arc
							(start 0.2032 0.2794)
							(mid 0.239121 0.264521)
							(end 0.254 0.2286)
						)
						(arc
							(start 0.254 -0.2286)
							(mid 0.239121 -0.264521)
							(end 0.2032 -0.2794)
						)
					)
					(width 0)
					(fill yes)
				)
			)
		)
		(pad "2" smd custom
			(at 0 0.4318)
			(size 0.127 0.127)
			(layers "F.Cu" "F.Mask" "F.Paste")
			(net "BOARD_PRSNT#")
			(options
				(clearance outline)
				(anchor circle)
			)
			(primitives
				(gr_poly
					(pts
						(arc
							(start -0.2032 -0.2794)
							(mid -0.239121 -0.264521)
							(end -0.254 -0.2286)
						)
						(arc
							(start -0.254 0.2286)
							(mid -0.239121 0.264521)
							(end -0.2032 0.2794)
						)
						(arc
							(start 0.2032 0.2794)
							(mid 0.239121 0.264521)
							(end 0.254 0.2286)
						)
						(arc
							(start 0.254 -0.2286)
							(mid 0.239121 -0.264521)
							(end 0.2032 -0.2794)
						)
					)
					(width 0)
					(fill yes)
				)
			)
		)
	)
	(footprint ""
		(layer "F.Cu")
		(at 153.035 -12.446 -90)
		(property "Reference" "R386"
			(at 0 0 270)
			(layer "F.SilkS")
			(hide yes)
			(effects
				(font
					(size 1.27 1.27)
				)
			)
		)
		(property "Value" "100R2F-L1-GP-U"
			(at 0.064008 -3.993896 270)
			(unlocked yes)
			(layer "F.Fab")
			(hide yes)
			(effects
				(font
					(size 1.016 1.016)
					(thickness 0.1524)
				)
			)
		)
		(property "Device Type" "R402H14"
			(at 0.064008 -5.517896 270)
			(unlocked yes)
			(layer "F.Fab")
			(hide yes)
			(effects
				(font
					(size 1.016 1.016)
					(thickness 0.1524)
				)
			)
		)
		(duplicate_pad_numbers_are_jumpers no)
		(fp_rect
			(start -0.381 0.8382)
			(end 0.381 -0.8382)
			(stroke
				(width 0)
				(type default)
			)
			(fill no)
			(layer "F.CrtYd")
		)
		(fp_rect
			(start -0.381 0.8382)
			(end 0.381 -0.8382)
			(stroke
				(width 0)
				(type default)
			)
			(fill no)
			(layer "F.Fab")
		)
		(pad "1" smd custom
			(at 0 -0.4318 270)
			(size 0.127 0.127)
			(layers "F.Cu" "F.Mask" "F.Paste")
			(net "DDR3_M_B_VREF_CA")
			(options
				(clearance outline)
				(anchor circle)
			)
			(primitives
				(gr_poly
					(pts
						(arc
							(start -0.2032 -0.2794)
							(mid -0.239121 -0.264521)
							(end -0.254 -0.2286)
						)
						(arc
							(start -0.254 0.2286)
							(mid -0.239121 0.264521)
							(end -0.2032 0.2794)
						)
						(arc
							(start 0.2032 0.2794)
							(mid 0.239121 0.264521)
							(end 0.254 0.2286)
						)
						(arc
							(start 0.254 -0.2286)
							(mid 0.239121 -0.264521)
							(end 0.2032 -0.2794)
						)
					)
					(width 0)
					(fill yes)
				)
			)
		)
		(pad "2" smd custom
			(at 0 0.4318 270)
			(size 0.127 0.127)
			(layers "F.Cu" "F.Mask" "F.Paste")
			(net "GND")
			(options
				(clearance outline)
				(anchor circle)
			)
			(primitives
				(gr_poly
					(pts
						(arc
							(start -0.2032 -0.2794)
							(mid -0.239121 -0.264521)
							(end -0.254 -0.2286)
						)
						(arc
							(start -0.254 0.2286)
							(mid -0.239121 0.264521)
							(end -0.2032 0.2794)
						)
						(arc
							(start 0.2032 0.2794)
							(mid 0.239121 0.264521)
							(end 0.254 0.2286)
						)
						(arc
							(start 0.254 -0.2286)
							(mid 0.239121 -0.264521)
							(end 0.2032 -0.2794)
						)
					)
					(width 0)
					(fill yes)
				)
			)
		)
	)
	(footprint ""
		(layer "F.Cu")
		(at 26.416 -49.276 -90)
		(property "Reference" "PC68"
			(at 0 0 270)
			(layer "F.SilkS")
			(hide yes)
			(effects
				(font
					(size 1.27 1.27)
				)
			)
		)
		(property "Value" "SCD33U6D3V2KX-1-GP"
			(at 1.8923 -1.2065 270)
			(unlocked yes)
			(layer "F.Fab")
			(hide yes)
			(effects
				(font
					(size 1.016 1.016)
					(thickness 0.1524)
				)
			)
		)
		(property "Device Type" "C402H22"
			(at 1.8923 -2.7305 270)
			(unlocked yes)
			(layer "F.Fab")
			(hide yes)
			(effects
				(font
					(size 1.016 1.016)
					(thickness 0.1524)
				)
			)
		)
		(duplicate_pad_numbers_are_jumpers no)
		(fp_rect
			(start -0.381 0.7366)
			(end 0.381 -0.7366)
			(stroke
				(width 0)
				(type default)
			)
			(fill no)
			(layer "F.CrtYd")
		)
		(fp_rect
			(start -0.381 0.7366)
			(end 0.381 -0.7366)
			(stroke
				(width 0)
				(type default)
			)
			(fill no)
			(layer "F.Fab")
		)
		(pad "1" smd custom
			(at 0 -0.4572 270)
			(size 0.1143 0.1143)
			(layers "F.Cu" "F.Mask" "F.Paste")
			(net "VR_PVCCP_ISUMP")
			(options
				(clearance outline)
				(anchor circle)
			)
			(primitives
				(gr_poly
					(pts
						(arc
							(start -0.254 -0.1778)
							(mid -0.239121 -0.213721)
							(end -0.2032 -0.2286)
						)
						(arc
							(start 0.2032 -0.2286)
							(mid 0.239121 -0.213721)
							(end 0.254 -0.1778)
						)
						(arc
							(start 0.254 0.1778)
							(mid 0.239121 0.213721)
							(end 0.2032 0.2286)
						)
						(arc
							(start -0.2032 0.2286)
							(mid -0.239121 0.213721)
							(end -0.254 0.1778)
						)
					)
					(width 0)
					(fill yes)
				)
			)
		)
		(pad "2" smd custom
			(at 0 0.4572 270)
			(size 0.1143 0.1143)
			(layers "F.Cu" "F.Mask" "F.Paste")
			(net "VR_PVCCP_ISUMN")
			(options
				(clearance outline)
				(anchor circle)
			)
			(primitives
				(gr_poly
					(pts
						(arc
							(start -0.254 -0.1778)
							(mid -0.239121 -0.213721)
							(end -0.2032 -0.2286)
						)
						(arc
							(start 0.2032 -0.2286)
							(mid 0.239121 -0.213721)
							(end 0.254 -0.1778)
						)
						(arc
							(start 0.254 0.1778)
							(mid 0.239121 0.213721)
							(end 0.2032 0.2286)
						)
						(arc
							(start -0.2032 0.2286)
							(mid -0.239121 0.213721)
							(end -0.254 0.1778)
						)
					)
					(width 0)
					(fill yes)
				)
			)
		)
	)
	(footprint ""
		(layer "F.Cu")
		(at 203.4794 -56.4642 90)
		(property "Reference" "PC162"
			(at 0 0 90)
			(layer "F.SilkS")
			(hide yes)
			(effects
				(font
					(size 1.27 1.27)
				)
			)
		)
		(property "Value" "SC22U6D3V5MX-2GP"
			(at 0 -4.9022 90)
			(unlocked yes)
			(layer "F.Fab")
			(hide yes)
			(effects
				(font
					(size 1.016 1.016)
					(thickness 0.1524)
				)
			)
		)
		(property "Device Type" "C805H58"
			(at 0 -6.8072 90)
			(unlocked yes)
			(layer "F.Fab")
			(hide yes)
			(effects
				(font
					(size 1.016 1.016)
					(thickness 0.1524)
				)
			)
		)
		(duplicate_pad_numbers_are_jumpers no)
		(fp_line
			(start 0.6096 0)
			(end -0.6096 0)
			(stroke
				(width 0.3048)
				(type default)
			)
			(layer "F.SilkS")
		)
		(fp_poly
			(pts
				(xy -0.9017 1.4351) (xy 0.9017 1.4351) (xy 0.9017 -1.4351) (xy -0.9017 -1.4351)
			)
			(stroke
				(width 0)
				(type default)
			)
			(fill no)
			(layer "F.CrtYd")
		)
		(fp_poly
			(pts
				(xy 0.9017 1.4351) (xy 0.9017 -1.4351) (xy -0.9017 -1.4351) (xy -0.9017 1.4351)
			)
			(stroke
				(width 0)
				(type default)
			)
			(fill no)
			(layer "F.Fab")
		)
		(pad "1" smd rect
			(at 0 -0.8382 90)
			(size 1.5494 0.9398)
			(layers "F.Cu" "F.Mask" "F.Paste")
			(net "PV_VDDR")
		)
		(pad "2" smd rect
			(at 0 0.8382 90)
			(size 1.5494 0.9398)
			(layers "F.Cu" "F.Mask" "F.Paste")
			(net "GND")
		)
	)
	(footprint ""
		(layer "F.Cu")
		(at 15.875 -68.453 90)
		(property "Reference" "R315"
			(at 0 0 90)
			(layer "F.SilkS")
			(hide yes)
			(effects
				(font
					(size 1.27 1.27)
				)
			)
		)
		(property "Value" "4K7R2F-GP"
			(at 1.7907 -1.1176 90)
			(unlocked yes)
			(layer "F.Fab")
			(hide yes)
			(effects
				(font
					(size 1.016 1.016)
					(thickness 0.1524)
				)
			)
		)
		(property "Device Type" "R402H16"
			(at 1.7907 -2.6416 90)
			(unlocked yes)
			(layer "F.Fab")
			(hide yes)
			(effects
				(font
					(size 1.016 1.016)
					(thickness 0.1524)
				)
			)
		)
		(duplicate_pad_numbers_are_jumpers no)
		(fp_rect
			(start -0.381 0.8382)
			(end 0.381 -0.8382)
			(stroke
				(width 0)
				(type default)
			)
			(fill no)
			(layer "F.CrtYd")
		)
		(fp_rect
			(start -0.381 0.8382)
			(end 0.381 -0.8382)
			(stroke
				(width 0)
				(type default)
			)
			(fill no)
			(layer "F.Fab")
		)
		(pad "1" smd custom
			(at 0 -0.4318 90)
			(size 0.127 0.127)
			(layers "F.Cu" "F.Mask" "F.Paste")
			(net "P3V3")
			(options
				(clearance outline)
				(anchor circle)
			)
			(primitives
				(gr_poly
					(pts
						(arc
							(start -0.2032 -0.2794)
							(mid -0.239121 -0.264521)
							(end -0.254 -0.2286)
						)
						(arc
							(start -0.254 0.2286)
							(mid -0.239121 0.264521)
							(end -0.2032 0.2794)
						)
						(arc
							(start 0.2032 0.2794)
							(mid 0.239121 0.264521)
							(end 0.254 0.2286)
						)
						(arc
							(start 0.254 -0.2286)
							(mid 0.239121 -0.264521)
							(end 0.2032 -0.2794)
						)
					)
					(width 0)
					(fill yes)
				)
			)
		)
		(pad "2" smd custom
			(at 0 0.4318 90)
			(size 0.127 0.127)
			(layers "F.Cu" "F.Mask" "F.Paste")
			(net "LED_NGFF_DAS")
			(options
				(clearance outline)
				(anchor circle)
			)
			(primitives
				(gr_poly
					(pts
						(arc
							(start -0.2032 -0.2794)
							(mid -0.239121 -0.264521)
							(end -0.254 -0.2286)
						)
						(arc
							(start -0.254 0.2286)
							(mid -0.239121 0.264521)
							(end -0.2032 0.2794)
						)
						(arc
							(start 0.2032 0.2794)
							(mid 0.239121 0.264521)
							(end 0.254 0.2286)
						)
						(arc
							(start 0.254 -0.2286)
							(mid 0.239121 -0.264521)
							(end 0.2032 -0.2794)
						)
					)
					(width 0)
					(fill yes)
				)
			)
		)
	)
	(footprint ""
		(layer "F.Cu")
		(at 148.2598 -49.4665 -90)
		(property "Reference" "U50"
			(at 0 0 270)
			(layer "F.SilkS")
			(hide yes)
			(effects
				(font
					(size 1.27 1.27)
				)
			)
		)
		(property "Value" "74CBTLV3257RG-1GP"
			(at 0 -8.5852 270)
			(unlocked yes)
			(layer "F.Fab")
			(hide yes)
			(effects
				(font
					(size 1.016 1.016)
					(thickness 0.1524)
				)
			)
		)
		(property "Device Type" "QFN16-G3H40"
			(at 0 -10.1092 270)
			(unlocked yes)
			(layer "F.Fab")
			(hide yes)
			(effects
				(font
					(size 1.016 1.016)
					(thickness 0.1524)
				)
			)
		)
		(duplicate_pad_numbers_are_jumpers no)
		(fp_line
			(start -2.4638 2.2098)
			(end -1.6002 2.2098)
			(stroke
				(width 0.1524)
				(type default)
			)
			(layer "F.SilkS")
		)
		(fp_line
			(start -1.6002 2.2098)
			(end -1.6002 2.0701)
			(stroke
				(width 0.1524)
				(type default)
			)
			(layer "F.SilkS")
		)
		(fp_line
			(start -2.3241 2.0701)
			(end -2.3241 1.0922)
			(stroke
				(width 0.1524)
				(type default)
			)
			(layer "F.SilkS")
		)
		(fp_line
			(start -1.6002 2.0701)
			(end -2.3241 2.0701)
			(stroke
				(width 0.1524)
				(type default)
			)
			(layer "F.SilkS")
		)
		(fp_line
			(start -2.1844 1.9304)
			(end -2.1844 1.0922)
			(stroke
				(width 0.1524)
				(type default)
			)
			(layer "F.SilkS")
		)
		(fp_line
			(start -1.6002 1.9304)
			(end -1.6002 2.0701)
			(stroke
				(width 0.1524)
				(type default)
			)
			(layer "F.SilkS")
		)
		(fp_line
			(start -1.6002 1.9304)
			(end -2.1844 1.9304)
			(stroke
				(width 0.1524)
				(type default)
			)
			(layer "F.SilkS")
		)
		(fp_line
			(start -2.4638 1.0922)
			(end -2.4638 2.2098)
			(stroke
				(width 0.1524)
				(type default)
			)
			(layer "F.SilkS")
		)
		(fp_line
			(start -2.3241 1.0922)
			(end -2.4638 1.0922)
			(stroke
				(width 0.1524)
				(type default)
			)
			(layer "F.SilkS")
		)
		(fp_line
			(start -2.3241 1.0922)
			(end -2.1844 1.0922)
			(stroke
				(width 0.1524)
				(type default)
			)
			(layer "F.SilkS")
		)
		(fp_poly
			(pts
				(xy -1.6002 2.2352) (xy -1.6002 1.9304) (xy -2.1844 1.9304) (xy -2.1844 1.0922) (xy -2.4892 1.0922)
				(xy -2.4892 -1.0922) (xy -2.1844 -1.0922) (xy -2.1844 -1.9304) (xy -1.6002 -1.9304) (xy -1.6002 -2.2352)
				(xy 1.6002 -2.2352) (xy 1.6002 -1.9304) (xy 2.1844 -1.9304) (xy 2.1844 -1.0922) (xy 2.4892 -1.0922)
				(xy 2.4892 1.0922) (xy 2.1844 1.0922) (xy 2.1844 1.9304) (xy 1.6002 1.9304) (xy 1.6002 2.2352)
			)
			(stroke
				(width 0)
				(type default)
			)
			(fill no)
			(layer "F.CrtYd")
		)
		(fp_poly
			(pts
				(xy -1.6002 2.2352) (xy -1.6002 1.9304) (xy -2.1844 1.9304) (xy -2.1844 1.0922) (xy -2.4892 1.0922)
				(xy -2.4892 -1.0922) (xy -2.1844 -1.0922) (xy -2.1844 -1.9304) (xy -1.6002 -1.9304) (xy -1.6002 -2.2352)
				(xy 1.6002 -2.2352) (xy 1.6002 -1.9304) (xy 2.1844 -1.9304) (xy 2.1844 -1.0922) (xy 2.4892 -1.0922)
				(xy 2.4892 1.0922) (xy 2.1844 1.0922) (xy 2.1844 1.9304) (xy 1.6002 1.9304) (xy 1.6002 2.2352)
			)
			(stroke
				(width 0)
				(type default)
			)
			(fill no)
			(layer "F.Fab")
		)
		(pad "1" smd rect
			(at -1.9558 0.75057 270)
			(size 0.7112 0.3048)
			(layers "F.Cu" "F.Mask" "F.Paste")
			(net "BUS_SW_SEL")
		)
		(pad "2" smd rect
			(at -1.24968 1.7018 270)
			(size 0.3048 0.7112)
			(layers "F.Cu" "F.Mask" "F.Paste")
			(net "SPI_SW_CSO#")
		)
		(pad "3" smd rect
			(at -0.75057 1.7018 270)
			(size 0.3048 0.7112)
			(layers "F.Cu" "F.Mask" "F.Paste")
			(net "FPGA_CSO#")
		)
		(pad "4" smd rect
			(at -0.25019 1.7018 270)
			(size 0.3048 0.7112)
			(layers "F.Cu" "F.Mask" "F.Paste")
			(net "C_CSO#")
		)
		(pad "5" smd rect
			(at 0.25019 1.7018 270)
			(size 0.3048 0.7112)
			(layers "F.Cu" "F.Mask" "F.Paste")
			(net "SPI_SW_DCLK")
		)
		(pad "6" smd rect
			(at 0.75057 1.7018 270)
			(size 0.3048 0.7112)
			(layers "F.Cu" "F.Mask" "F.Paste")
			(net "FPGA_DCLK")
		)
		(pad "7" smd rect
			(at 1.24968 1.7018 270)
			(size 0.3048 0.7112)
			(layers "F.Cu" "F.Mask" "F.Paste")
			(net "C_DCLK")
		)
		(pad "8" smd rect
			(at 1.9558 0.75057 270)
			(size 0.7112 0.3048)
			(layers "F.Cu" "F.Mask" "F.Paste")
			(net "GND")
		)
		(pad "9" smd rect
			(at 1.9558 -0.75057 270)
			(size 0.7112 0.3048)
			(layers "F.Cu" "F.Mask" "F.Paste")
			(net "C_ASDO")
		)
		(pad "10" smd rect
			(at 1.24968 -1.7018 270)
			(size 0.3048 0.7112)
			(layers "F.Cu" "F.Mask" "F.Paste")
			(net "FPGA_ASDO")
		)
		(pad "11" smd rect
			(at 0.75057 -1.7018 270)
			(size 0.3048 0.7112)
			(layers "F.Cu" "F.Mask" "F.Paste")
			(net "SPI_SW_ASDO")
		)
		(pad "12" smd rect
			(at 0.25019 -1.7018 270)
			(size 0.3048 0.7112)
			(layers "F.Cu" "F.Mask" "F.Paste")
			(net "C_DATA0")
		)
		(pad "13" smd rect
			(at -0.25019 -1.7018 270)
			(size 0.3048 0.7112)
			(layers "F.Cu" "F.Mask" "F.Paste")
			(net "FPGA_DATA0")
		)
		(pad "14" smd rect
			(at -0.75057 -1.7018 270)
			(size 0.3048 0.7112)
			(layers "F.Cu" "F.Mask" "F.Paste")
			(net "SPI_SW_DATA0")
		)
		(pad "15" smd rect
			(at -1.24968 -1.7018 270)
			(size 0.3048 0.7112)
			(layers "F.Cu" "F.Mask" "F.Paste")
			(net "BUS_SW_OE#")
		)
		(pad "16" smd rect
			(at -1.9558 -0.75057 270)
			(size 0.7112 0.3048)
			(layers "F.Cu" "F.Mask" "F.Paste")
			(net "P3V3_STBY")
		)
		(pad "17" smd rect
			(at 0 0 270)
			(size 2.1844 1.6764)
			(layers "F.Cu" "F.Mask" "F.Paste")
			(net "GND")
		)
	)
)
